# S9S_MB_2U (Grand Teton) — schematic netlist excerpt (pin names and nets, part order shuffled) for the footprints in the layout excerpt that follows; sources: Cadence DE-HDL packaged netlist, KiCad conversion of 03242023_DA0F0TMBIJ0_F0T_Motherboard_J_brd_V01_OCP.brd

PC1344  Q_CAP  0.1UF 25V 10% X7R  pkg 0402  page 270 : A = GND ; B = PVCCIN_CPU0_VREF
R497  Q_RES  200 1% CHIP  pkg 0402LF  page 187 : A = PD_RCOMP_1P8_3P3 ; B = GND

PR4  Q_SP_RES4P  0.0003 1% EMPTY  pkg R2725_4P  page 304
  \1a\  = P12V_PSU
  \1b\  = P12V_HSC_SENSE2_R1_P
  \2a\  = P12V_MAIN_R
  \2b\  = P12V_HSC_SENSE2_R1_N

(kicad_pcb
	(version 20260206)
	(generator "pcbnew")
	(generator_version "10.0")
	(general
		(thickness 1.6)
		(legacy_teardrops no)
	)
	(paper "A4")
	(title_block
		(title "03242023_DA0F0TMBIJ0_F0T_Motherboard_J_brd_V01_OCP.brd")
		(comment 1 "Grand Teton / footprints 3642-3644 of 6105")
	)
	(layers
		(0 "F.Cu" signal "TOP")
		(4 "In1.Cu" signal "GND")
		(6 "In2.Cu" signal "IN1")
		(8 "In3.Cu" signal "GND1")
		(10 "In4.Cu" signal "IN2")
		(12 "In5.Cu" signal "GND2")
		(14 "In6.Cu" signal "IN3")
		(16 "In7.Cu" signal "GND3")
		(18 "In8.Cu" signal "VCC")
		(20 "In9.Cu" signal "VCC1")
		(22 "In10.Cu" signal "GND4")
		(24 "In11.Cu" signal "IN4")
		(26 "In12.Cu" signal "GND5")
		(28 "In13.Cu" signal "IN5")
		(30 "In14.Cu" signal "GND6")
		(32 "In15.Cu" signal "IN6")
		(34 "In16.Cu" signal "GND7")
		(2 "B.Cu" signal "BOTTOM")
		(9 "F.Adhes" user "F.Adhesive")
		(11 "B.Adhes" user "B.Adhesive")
		(13 "F.Paste" user "Package Geometry/Pastemask Top")
		(15 "B.Paste" user "Package Geometry/Pastemask Bottom")
		(5 "F.SilkS" user "Ref Des/Silkscreen Top")
		(7 "B.SilkS" user "Ref Des/Silkscreen Bottom")
		(1 "F.Mask" user "Board Geometry/Soldermask Top")
		(3 "B.Mask" user "Board Geometry/Soldermask Bottom")
		(17 "Dwgs.User" user "User.Drawings")
		(19 "Cmts.User" user "User.Comments")
		(21 "Eco1.User" user "User.Eco1")
		(23 "Eco2.User" user "User.Eco2")
		(25 "Edge.Cuts" user "Board Geometry/Outline")
		(27 "Margin" user)
		(31 "F.CrtYd" user "Package Geometry/Place Bound Top")
		(29 "B.CrtYd" user "Package Geometry/Place Bound Bottom")
		(35 "F.Fab" user "Ref Des/Assembly Top")
		(33 "B.Fab" user "Ref Des/Assembly Bottom")
	)
	(footprint ""
		(layer "F.Cu")
		(at 382.968754 -347.509846 -90)
		(property "Reference" "PC1344"
			(at 0 0 270)
			(layer "F.SilkS")
			(hide yes)
			(effects
				(font
					(size 1.27 1.27)
				)
			)
		)
		(property "Value" ""
			(at 0 0 270)
			(layer "F.Fab")
			(effects
				(font
					(size 1.27 1.27)
				)
			)
		)
		(duplicate_pad_numbers_are_jumpers no)
		(fp_line
			(start -0.7874 0.4064)
			(end -0.7874 -0.4064)
			(stroke
				(width 0.1524)
				(type default)
			)
			(layer "F.SilkS")
		)
		(fp_line
			(start 0.7874 0.4064)
			(end -0.7874 0.4064)
			(stroke
				(width 0.1524)
				(type default)
			)
			(layer "F.SilkS")
		)
		(fp_line
			(start -0.7874 -0.4064)
			(end 0.7874 -0.4064)
			(stroke
				(width 0.1524)
				(type default)
			)
			(layer "F.SilkS")
		)
		(fp_line
			(start 0.7874 -0.4064)
			(end 0.7874 0.4064)
			(stroke
				(width 0.1524)
				(type default)
			)
			(layer "F.SilkS")
		)
		(fp_line
			(start -0.67945 0.3048)
			(end -0.67945 -0.305054)
			(stroke
				(width 0.1)
				(type default)
			)
			(layer "F.Fab")
		)
		(fp_line
			(start -0.12065 0.3048)
			(end -0.67945 0.3048)
			(stroke
				(width 0.1)
				(type default)
			)
			(layer "F.Fab")
		)
		(fp_line
			(start 0.120396 0.3048)
			(end 0.120396 0.2794)
			(stroke
				(width 0.1)
				(type default)
			)
			(layer "F.Fab")
		)
		(fp_line
			(start 0.67945 0.3048)
			(end 0.120396 0.3048)
			(stroke
				(width 0.1)
				(type default)
			)
			(layer "F.Fab")
		)
		(fp_line
			(start -0.12065 0.2794)
			(end -0.12065 0.3048)
			(stroke
				(width 0.1)
				(type default)
			)
			(layer "F.Fab")
		)
		(fp_line
			(start 0.120396 0.2794)
			(end -0.12065 0.2794)
			(stroke
				(width 0.1)
				(type default)
			)
			(layer "F.Fab")
		)
		(fp_line
			(start -0.12065 -0.2794)
			(end 0.12065 -0.2794)
			(stroke
				(width 0.1)
				(type default)
			)
			(layer "F.Fab")
		)
		(fp_line
			(start 0.12065 -0.2794)
			(end 0.12065 -0.3048)
			(stroke
				(width 0.1)
				(type default)
			)
			(layer "F.Fab")
		)
		(fp_line
			(start 0.12065 -0.3048)
			(end 0.67945 -0.3048)
			(stroke
				(width 0.1)
				(type default)
			)
			(layer "F.Fab")
		)
		(fp_line
			(start 0.67945 -0.3048)
			(end 0.67945 0.3048)
			(stroke
				(width 0.1)
				(type default)
			)
			(layer "F.Fab")
		)
		(fp_line
			(start -0.67945 -0.305054)
			(end -0.12065 -0.305054)
			(stroke
				(width 0.1)
				(type default)
			)
			(layer "F.Fab")
		)
		(fp_line
			(start -0.12065 -0.305054)
			(end -0.12065 -0.2794)
			(stroke
				(width 0.1)
				(type default)
			)
			(layer "F.Fab")
		)
		(pad "1" smd circle
			(at -0.40005 0 270)
			(size 0 0)
			(layers "F.Cu" "F.Mask" "F.Paste")
			(net "GND")
		)
		(pad "2" smd circle
			(at 0.40005 0 270)
			(size 0 0)
			(layers "F.Cu" "F.Mask" "F.Paste")
			(net "PVCCIN_CPU0_VREF")
		)
	)
	(footprint ""
		(layer "F.Cu")
		(at 307.14188 -49.621948 180)
		(property "Reference" "R497"
			(at 0 0 180)
			(layer "F.SilkS")
			(hide yes)
			(effects
				(font
					(size 1.27 1.27)
				)
			)
		)
		(property "Value" ""
			(at 0 0 180)
			(layer "F.Fab")
			(effects
				(font
					(size 1.27 1.27)
				)
			)
		)
		(duplicate_pad_numbers_are_jumpers no)
		(fp_line
			(start 0.7874 0.4064)
			(end -0.7874 0.4064)
			(stroke
				(width 0.1524)
				(type default)
			)
			(layer "F.SilkS")
		)
		(fp_line
			(start 0.7874 -0.4064)
			(end 0.7874 0.4064)
			(stroke
				(width 0.1524)
				(type default)
			)
			(layer "F.SilkS")
		)
		(fp_line
			(start -0.7874 0.4064)
			(end -0.7874 -0.4064)
			(stroke
				(width 0.1524)
				(type default)
			)
			(layer "F.SilkS")
		)
		(fp_line
			(start -0.7874 -0.4064)
			(end 0.7874 -0.4064)
			(stroke
				(width 0.1524)
				(type default)
			)
			(layer "F.SilkS")
		)
		(fp_line
			(start 0.67945 0.3048)
			(end 0.120396 0.3048)
			(stroke
				(width 0.1)
				(type default)
			)
			(layer "F.Fab")
		)
		(fp_line
			(start 0.67945 -0.3048)
			(end 0.67945 0.3048)
			(stroke
				(width 0.1)
				(type default)
			)
			(layer "F.Fab")
		)
		(fp_line
			(start 0.12065 -0.2794)
			(end 0.12065 -0.3048)
			(stroke
				(width 0.1)
				(type default)
			)
			(layer "F.Fab")
		)
		(fp_line
			(start 0.12065 -0.3048)
			(end 0.67945 -0.3048)
			(stroke
				(width 0.1)
				(type default)
			)
			(layer "F.Fab")
		)
		(fp_line
			(start 0.120396 0.3048)
			(end 0.120396 0.2794)
			(stroke
				(width 0.1)
				(type default)
			)
			(layer "F.Fab")
		)
		(fp_line
			(start 0.120396 0.2794)
			(end -0.12065 0.2794)
			(stroke
				(width 0.1)
				(type default)
			)
			(layer "F.Fab")
		)
		(fp_line
			(start -0.12065 0.3048)
			(end -0.67945 0.3048)
			(stroke
				(width 0.1)
				(type default)
			)
			(layer "F.Fab")
		)
		(fp_line
			(start -0.12065 0.2794)
			(end -0.12065 0.3048)
			(stroke
				(width 0.1)
				(type default)
			)
			(layer "F.Fab")
		)
		(fp_line
			(start -0.12065 -0.2794)
			(end 0.12065 -0.2794)
			(stroke
				(width 0.1)
				(type default)
			)
			(layer "F.Fab")
		)
		(fp_line
			(start -0.12065 -0.305054)
			(end -0.12065 -0.2794)
			(stroke
				(width 0.1)
				(type default)
			)
			(layer "F.Fab")
		)
		(fp_line
			(start -0.67945 0.3048)
			(end -0.67945 -0.305054)
			(stroke
				(width 0.1)
				(type default)
			)
			(layer "F.Fab")
		)
		(fp_line
			(start -0.67945 -0.305054)
			(end -0.12065 -0.305054)
			(stroke
				(width 0.1)
				(type default)
			)
			(layer "F.Fab")
		)
		(pad "1" smd circle
			(at -0.40005 0 180)
			(size 0 0)
			(layers "F.Cu" "F.Mask" "F.Paste")
			(net "PD_RCOMP_1P8_3P3")
		)
		(pad "2" smd circle
			(at 0.40005 0 180)
			(size 0 0)
			(layers "F.Cu" "F.Mask" "F.Paste")
			(net "GND")
		)
	)
	(footprint ""
		(layer "F.Cu")
		(at 244.750844 -407.411936 -90)
		(property "Reference" "PR4"
			(at 0 0 270)
			(layer "F.SilkS")
			(hide yes)
			(effects
				(font
					(size 1.27 1.27)
				)
			)
		)
		(property "Value" ""
			(at 0 0 270)
			(layer "F.Fab")
			(effects
				(font
					(size 1.27 1.27)
				)
			)
		)
		(duplicate_pad_numbers_are_jumpers no)
		(fp_line
			(start -3.9878 3.5814)
			(end -3.9878 -3.5814)
			(stroke
				(width 0.1524)
				(type default)
			)
			(layer "F.SilkS")
		)
		(fp_line
			(start 3.9878 3.5814)
			(end -3.9878 3.5814)
			(stroke
				(width 0.1524)
				(type default)
			)
			(layer "F.SilkS")
		)
		(fp_line
			(start -3.9878 -3.5814)
			(end 3.9878 -3.5814)
			(stroke
				(width 0.1524)
				(type default)
			)
			(layer "F.SilkS")
		)
		(fp_line
			(start 3.9878 -3.5814)
			(end 3.9878 3.5814)
			(stroke
				(width 0.1524)
				(type default)
			)
			(layer "F.SilkS")
		)
		(fp_line
			(start -3.5306 3.353054)
			(end -3.5306 -3.353054)
			(stroke
				(width 0.1)
				(type default)
			)
			(layer "F.Fab")
		)
		(fp_line
			(start 3.5306 3.353054)
			(end -3.5306 3.353054)
			(stroke
				(width 0.1)
				(type default)
			)
			(layer "F.Fab")
		)
		(fp_line
			(start -3.5306 -3.353054)
			(end 3.5306 -3.353054)
			(stroke
				(width 0.1)
				(type default)
			)
			(layer "F.Fab")
		)
		(fp_line
			(start 3.5306 -3.353054)
			(end 3.5306 3.353054)
			(stroke
				(width 0.1)
				(type default)
			)
			(layer "F.Fab")
		)
		(pad "1A" smd rect
			(at -2.249932 0 90)
			(size 3.2004 6.858)
			(layers "F.Cu" "F.Mask" "F.Paste")
			(net "P12V_PSU")
		)
		(pad "1B" smd rect
			(at -0.776732 0 270)
			(size 0.254 0.508)
			(layers "F.Cu" "F.Mask" "F.Paste")
			(net "P12V_HSC_SENSE2_R1_P")
		)
		(pad "2A" smd rect
			(at 2.249932 0 90)
			(size 3.2004 6.858)
			(layers "F.Cu" "F.Mask" "F.Paste")
			(net "P12V_MAIN_R")
		)
		(pad "2B" smd rect
			(at 0.776732 0 270)
			(size 0.254 0.508)
			(layers "F.Cu" "F.Mask" "F.Paste")
			(net "P12V_HSC_SENSE2_R1_N")
		)
	)
)
